(kicad_pcb
	(version 20260206)
	(generator "pcbnew")
	(generator_version "10.0")
	(general
		(thickness 1.6)
		(legacy_teardrops no)
	)
	(paper "A4")
	(title_block
		(title "01162023_DA0F0TEBIF0_F0T_Expander_BD_F_brd_V02_OCP.brd")
		(comment 1 "Grand Teton / footprints 3682-3688 of 9728")
	)
	(layers
		(0 "F.Cu" signal "TOP")
		(4 "In1.Cu" signal "GND")
		(6 "In2.Cu" signal "VCC")
		(8 "In3.Cu" signal "VCC1")
		(10 "In4.Cu" signal "GND1")
		(12 "In5.Cu" signal "IN1")
		(14 "In6.Cu" signal "GND2")
		(16 "In7.Cu" signal "IN2")
		(18 "In8.Cu" signal "GND3")
		(20 "In9.Cu" signal "IN3")
		(22 "In10.Cu" signal "GND4")
		(24 "In11.Cu" signal "IN4")
		(26 "In12.Cu" signal "GND5")
		(28 "In13.Cu" signal "IN5")
		(30 "In14.Cu" signal "GND6")
		(32 "In15.Cu" signal "IN6")
		(34 "In16.Cu" signal "GND7")
		(2 "B.Cu" signal "BOTTOM")
		(9 "F.Adhes" user "F.Adhesive")
		(11 "B.Adhes" user "B.Adhesive")
		(13 "F.Paste" user "Package Geometry/Pastemask Top")
		(15 "B.Paste" user "Package Geometry/Pastemask Bottom")
		(5 "F.SilkS" user "Ref Des/Silkscreen Top")
		(7 "B.SilkS" user "Ref Des/Silkscreen Bottom")
		(1 "F.Mask" user "Board Geometry/Soldermask Top")
		(3 "B.Mask" user "Board Geometry/Soldermask Bottom")
		(17 "Dwgs.User" user "User.Drawings")
		(19 "Cmts.User" user "User.Comments")
		(21 "Eco1.User" user "User.Eco1")
		(23 "Eco2.User" user "User.Eco2")
		(25 "Edge.Cuts" user "Board Geometry/Outline")
		(27 "Margin" user)
		(31 "F.CrtYd" user "Package Geometry/Place Bound Top")
		(29 "B.CrtYd" user "Package Geometry/Place Bound Bottom")
		(35 "F.Fab" user "Ref Des/Assembly Top")
		(33 "B.Fab" user "Ref Des/Assembly Bottom")
	)
	(footprint ""
		(layer "F.Cu")
		(at 439.33364 -304.036476 90)
		(property "Reference" "R1453"
			(at 0 0 90)
			(layer "F.SilkS")
			(hide yes)
			(effects
				(font
					(size 1.27 1.27)
				)
			)
		)
		(property "Value" ""
			(at 0 0 90)
			(layer "F.Fab")
			(effects
				(font
					(size 1.27 1.27)
				)
			)
		)
		(duplicate_pad_numbers_are_jumpers no)
		(fp_line
			(start 0.7874 -0.4064)
			(end 0.7874 0.4064)
			(stroke
				(width 0.1524)
				(type default)
			)
			(layer "F.SilkS")
		)
		(fp_line
			(start -0.7874 -0.4064)
			(end 0.7874 -0.4064)
			(stroke
				(width 0.1524)
				(type default)
			)
			(layer "F.SilkS")
		)
		(fp_line
			(start 0.7874 0.4064)
			(end -0.7874 0.4064)
			(stroke
				(width 0.1524)
				(type default)
			)
			(layer "F.SilkS")
		)
		(fp_line
			(start -0.7874 0.4064)
			(end -0.7874 -0.4064)
			(stroke
				(width 0.1524)
				(type default)
			)
			(layer "F.SilkS")
		)
		(fp_line
			(start -0.12065 -0.305054)
			(end -0.12065 -0.2794)
			(stroke
				(width 0.1)
				(type default)
			)
			(layer "F.Fab")
		)
		(fp_line
			(start -0.67945 -0.305054)
			(end -0.12065 -0.305054)
			(stroke
				(width 0.1)
				(type default)
			)
			(layer "F.Fab")
		)
		(fp_line
			(start 0.67945 -0.3048)
			(end 0.67945 0.3048)
			(stroke
				(width 0.1)
				(type default)
			)
			(layer "F.Fab")
		)
		(fp_line
			(start 0.12065 -0.3048)
			(end 0.67945 -0.3048)
			(stroke
				(width 0.1)
				(type default)
			)
			(layer "F.Fab")
		)
		(fp_line
			(start 0.12065 -0.2794)
			(end 0.12065 -0.3048)
			(stroke
				(width 0.1)
				(type default)
			)
			(layer "F.Fab")
		)
		(fp_line
			(start -0.12065 -0.2794)
			(end 0.12065 -0.2794)
			(stroke
				(width 0.1)
				(type default)
			)
			(layer "F.Fab")
		)
		(fp_line
			(start 0.120396 0.2794)
			(end -0.12065 0.2794)
			(stroke
				(width 0.1)
				(type default)
			)
			(layer "F.Fab")
		)
		(fp_line
			(start -0.12065 0.2794)
			(end -0.12065 0.3048)
			(stroke
				(width 0.1)
				(type default)
			)
			(layer "F.Fab")
		)
		(fp_line
			(start 0.67945 0.3048)
			(end 0.120396 0.3048)
			(stroke
				(width 0.1)
				(type default)
			)
			(layer "F.Fab")
		)
		(fp_line
			(start 0.120396 0.3048)
			(end 0.120396 0.2794)
			(stroke
				(width 0.1)
				(type default)
			)
			(layer "F.Fab")
		)
		(fp_line
			(start -0.12065 0.3048)
			(end -0.67945 0.3048)
			(stroke
				(width 0.1)
				(type default)
			)
			(layer "F.Fab")
		)
		(fp_line
			(start -0.67945 0.3048)
			(end -0.67945 -0.305054)
			(stroke
				(width 0.1)
				(type default)
			)
			(layer "F.Fab")
		)
		(pad "1" smd circle
			(at -0.40005 0 90)
			(size 0 0)
			(layers "F.Cu" "F.Mask" "F.Paste")
			(net "GND")
		)
		(pad "2" smd circle
			(at 0.40005 0 90)
			(size 0 0)
			(layers "F.Cu" "F.Mask" "F.Paste")
			(net "PEX3_SPARE1")
		)
	)
	(footprint ""
		(layer "F.Cu")
		(at 164.127942 -35.876738)
		(property "Reference" "R6070"
			(at 0 0 0)
			(layer "F.SilkS")
			(hide yes)
			(effects
				(font
					(size 1.27 1.27)
				)
			)
		)
		(property "Value" ""
			(at 0 0 0)
			(layer "F.Fab")
			(effects
				(font
					(size 1.27 1.27)
				)
			)
		)
		(duplicate_pad_numbers_are_jumpers no)
		(fp_line
			(start -0.7874 -0.4064)
			(end 0.7874 -0.4064)
			(stroke
				(width 0.1524)
				(type default)
			)
			(layer "F.SilkS")
		)
		(fp_line
			(start -0.7874 0.4064)
			(end -0.7874 -0.4064)
			(stroke
				(width 0.1524)
				(type default)
			)
			(layer "F.SilkS")
		)
		(fp_line
			(start 0.7874 -0.4064)
			(end 0.7874 0.4064)
			(stroke
				(width 0.1524)
				(type default)
			)
			(layer "F.SilkS")
		)
		(fp_line
			(start 0.7874 0.4064)
			(end -0.7874 0.4064)
			(stroke
				(width 0.1524)
				(type default)
			)
			(layer "F.SilkS")
		)
		(fp_line
			(start -0.67945 -0.305054)
			(end -0.12065 -0.305054)
			(stroke
				(width 0.1)
				(type default)
			)
			(layer "F.Fab")
		)
		(fp_line
			(start -0.67945 0.3048)
			(end -0.67945 -0.305054)
			(stroke
				(width 0.1)
				(type default)
			)
			(layer "F.Fab")
		)
		(fp_line
			(start -0.12065 -0.305054)
			(end -0.12065 -0.2794)
			(stroke
				(width 0.1)
				(type default)
			)
			(layer "F.Fab")
		)
		(fp_line
			(start -0.12065 -0.2794)
			(end 0.12065 -0.2794)
			(stroke
				(width 0.1)
				(type default)
			)
			(layer "F.Fab")
		)
		(fp_line
			(start -0.12065 0.2794)
			(end -0.12065 0.3048)
			(stroke
				(width 0.1)
				(type default)
			)
			(layer "F.Fab")
		)
		(fp_line
			(start -0.12065 0.3048)
			(end -0.67945 0.3048)
			(stroke
				(width 0.1)
				(type default)
			)
			(layer "F.Fab")
		)
		(fp_line
			(start 0.120396 0.2794)
			(end -0.12065 0.2794)
			(stroke
				(width 0.1)
				(type default)
			)
			(layer "F.Fab")
		)
		(fp_line
			(start 0.120396 0.3048)
			(end 0.120396 0.2794)
			(stroke
				(width 0.1)
				(type default)
			)
			(layer "F.Fab")
		)
		(fp_line
			(start 0.12065 -0.3048)
			(end 0.67945 -0.3048)
			(stroke
				(width 0.1)
				(type default)
			)
			(layer "F.Fab")
		)
		(fp_line
			(start 0.12065 -0.2794)
			(end 0.12065 -0.3048)
			(stroke
				(width 0.1)
				(type default)
			)
			(layer "F.Fab")
		)
		(fp_line
			(start 0.67945 -0.3048)
			(end 0.67945 0.3048)
			(stroke
				(width 0.1)
				(type default)
			)
			(layer "F.Fab")
		)
		(fp_line
			(start 0.67945 0.3048)
			(end 0.120396 0.3048)
			(stroke
				(width 0.1)
				(type default)
			)
			(layer "F.Fab")
		)
		(pad "1" smd circle
			(at -0.40005 0)
			(size 0 0)
			(layers "F.Cu" "F.Mask" "F.Paste")
			(net "PWRGD_P3V3_SSD6_D")
		)
		(pad "2" smd circle
			(at 0.40005 0)
			(size 0 0)
			(layers "F.Cu" "F.Mask" "F.Paste")
			(net "PWRGD_P3V3_SSD6_R")
		)
	)
	(footprint ""
		(layer "F.Cu")
		(at 379.633988 -5.852922)
		(property "Reference" "R5816"
			(at 0 0 0)
			(layer "F.SilkS")
			(hide yes)
			(effects
				(font
					(size 1.27 1.27)
				)
			)
		)
		(property "Value" ""
			(at 0 0 0)
			(layer "F.Fab")
			(effects
				(font
					(size 1.27 1.27)
				)
			)
		)
		(duplicate_pad_numbers_are_jumpers no)
		(fp_line
			(start -0.7874 -0.4064)
			(end 0.7874 -0.4064)
			(stroke
				(width 0.1524)
				(type default)
			)
			(layer "F.SilkS")
		)
		(fp_line
			(start -0.7874 0.4064)
			(end -0.7874 -0.4064)
			(stroke
				(width 0.1524)
				(type default)
			)
			(layer "F.SilkS")
		)
		(fp_line
			(start 0.7874 -0.4064)
			(end 0.7874 0.4064)
			(stroke
				(width 0.1524)
				(type default)
			)
			(layer "F.SilkS")
		)
		(fp_line
			(start 0.7874 0.4064)
			(end -0.7874 0.4064)
			(stroke
				(width 0.1524)
				(type default)
			)
			(layer "F.SilkS")
		)
		(fp_line
			(start -0.67945 -0.305054)
			(end -0.12065 -0.305054)
			(stroke
				(width 0.1)
				(type default)
			)
			(layer "F.Fab")
		)
		(fp_line
			(start -0.67945 0.3048)
			(end -0.67945 -0.305054)
			(stroke
				(width 0.1)
				(type default)
			)
			(layer "F.Fab")
		)
		(fp_line
			(start -0.12065 -0.305054)
			(end -0.12065 -0.2794)
			(stroke
				(width 0.1)
				(type default)
			)
			(layer "F.Fab")
		)
		(fp_line
			(start -0.12065 -0.2794)
			(end 0.12065 -0.2794)
			(stroke
				(width 0.1)
				(type default)
			)
			(layer "F.Fab")
		)
		(fp_line
			(start -0.12065 0.2794)
			(end -0.12065 0.3048)
			(stroke
				(width 0.1)
				(type default)
			)
			(layer "F.Fab")
		)
		(fp_line
			(start -0.12065 0.3048)
			(end -0.67945 0.3048)
			(stroke
				(width 0.1)
				(type default)
			)
			(layer "F.Fab")
		)
		(fp_line
			(start 0.120396 0.2794)
			(end -0.12065 0.2794)
			(stroke
				(width 0.1)
				(type default)
			)
			(layer "F.Fab")
		)
		(fp_line
			(start 0.120396 0.3048)
			(end 0.120396 0.2794)
			(stroke
				(width 0.1)
				(type default)
			)
			(layer "F.Fab")
		)
		(fp_line
			(start 0.12065 -0.3048)
			(end 0.67945 -0.3048)
			(stroke
				(width 0.1)
				(type default)
			)
			(layer "F.Fab")
		)
		(fp_line
			(start 0.12065 -0.2794)
			(end 0.12065 -0.3048)
			(stroke
				(width 0.1)
				(type default)
			)
			(layer "F.Fab")
		)
		(fp_line
			(start 0.67945 -0.3048)
			(end 0.67945 0.3048)
			(stroke
				(width 0.1)
				(type default)
			)
			(layer "F.Fab")
		)
		(fp_line
			(start 0.67945 0.3048)
			(end 0.120396 0.3048)
			(stroke
				(width 0.1)
				(type default)
			)
			(layer "F.Fab")
		)
		(pad "1" smd circle
			(at -0.40005 0)
			(size 0 0)
			(layers "F.Cu" "F.Mask" "F.Paste")
			(net "LM75_3_A1")
		)
		(pad "2" smd circle
			(at 0.40005 0)
			(size 0 0)
			(layers "F.Cu" "F.Mask" "F.Paste")
			(net "P3V3_AUX")
		)
	)
	(footprint ""
		(layer "F.Cu")
		(at 325.26605 -306.074572 90)
		(property "Reference" "R4181"
			(at 0 0 90)
			(layer "F.SilkS")
			(hide yes)
			(effects
				(font
					(size 1.27 1.27)
				)
			)
		)
		(property "Value" ""
			(at 0 0 90)
			(layer "F.Fab")
			(effects
				(font
					(size 1.27 1.27)
				)
			)
		)
		(duplicate_pad_numbers_are_jumpers no)
		(fp_line
			(start 0.7874 -0.4064)
			(end 0.7874 0.4064)
			(stroke
				(width 0.1524)
				(type default)
			)
			(layer "F.SilkS")
		)
		(fp_line
			(start -0.7874 -0.4064)
			(end 0.7874 -0.4064)
			(stroke
				(width 0.1524)
				(type default)
			)
			(layer "F.SilkS")
		)
		(fp_line
			(start 0.7874 0.4064)
			(end -0.7874 0.4064)
			(stroke
				(width 0.1524)
				(type default)
			)
			(layer "F.SilkS")
		)
		(fp_line
			(start -0.7874 0.4064)
			(end -0.7874 -0.4064)
			(stroke
				(width 0.1524)
				(type default)
			)
			(layer "F.SilkS")
		)
		(fp_line
			(start -0.12065 -0.305054)
			(end -0.12065 -0.2794)
			(stroke
				(width 0.1)
				(type default)
			)
			(layer "F.Fab")
		)
		(fp_line
			(start -0.67945 -0.305054)
			(end -0.12065 -0.305054)
			(stroke
				(width 0.1)
				(type default)
			)
			(layer "F.Fab")
		)
		(fp_line
			(start 0.67945 -0.3048)
			(end 0.67945 0.3048)
			(stroke
				(width 0.1)
				(type default)
			)
			(layer "F.Fab")
		)
		(fp_line
			(start 0.12065 -0.3048)
			(end 0.67945 -0.3048)
			(stroke
				(width 0.1)
				(type default)
			)
			(layer "F.Fab")
		)
		(fp_line
			(start 0.12065 -0.2794)
			(end 0.12065 -0.3048)
			(stroke
				(width 0.1)
				(type default)
			)
			(layer "F.Fab")
		)
		(fp_line
			(start -0.12065 -0.2794)
			(end 0.12065 -0.2794)
			(stroke
				(width 0.1)
				(type default)
			)
			(layer "F.Fab")
		)
		(fp_line
			(start 0.120396 0.2794)
			(end -0.12065 0.2794)
			(stroke
				(width 0.1)
				(type default)
			)
			(layer "F.Fab")
		)
		(fp_line
			(start -0.12065 0.2794)
			(end -0.12065 0.3048)
			(stroke
				(width 0.1)
				(type default)
			)
			(layer "F.Fab")
		)
		(fp_line
			(start 0.67945 0.3048)
			(end 0.120396 0.3048)
			(stroke
				(width 0.1)
				(type default)
			)
			(layer "F.Fab")
		)
		(fp_line
			(start 0.120396 0.3048)
			(end 0.120396 0.2794)
			(stroke
				(width 0.1)
				(type default)
			)
			(layer "F.Fab")
		)
		(fp_line
			(start -0.12065 0.3048)
			(end -0.67945 0.3048)
			(stroke
				(width 0.1)
				(type default)
			)
			(layer "F.Fab")
		)
		(fp_line
			(start -0.67945 0.3048)
			(end -0.67945 -0.305054)
			(stroke
				(width 0.1)
				(type default)
			)
			(layer "F.Fab")
		)
		(pad "1" smd circle
			(at -0.40005 0 90)
			(size 0 0)
			(layers "F.Cu" "F.Mask" "F.Paste")
			(net "PEX2_EXT_GPIO_LATCH_N")
		)
		(pad "2" smd circle
			(at 0.40005 0 90)
			(size 0 0)
			(layers "F.Cu" "F.Mask" "F.Paste")
			(net "P1V8_PEX")
		)
	)
	(footprint ""
		(layer "F.Cu")
		(at 407.009092 -26.03373)
		(property "Reference" "R4080"
			(at 0 0 0)
			(layer "F.SilkS")
			(hide yes)
			(effects
				(font
					(size 1.27 1.27)
				)
			)
		)
		(property "Value" ""
			(at 0 0 0)
			(layer "F.Fab")
			(effects
				(font
					(size 1.27 1.27)
				)
			)
		)
		(duplicate_pad_numbers_are_jumpers no)
		(fp_line
			(start -0.7874 -0.4064)
			(end 0.7874 -0.4064)
			(stroke
				(width 0.1524)
				(type default)
			)
			(layer "F.SilkS")
		)
		(fp_line
			(start -0.7874 0.4064)
			(end -0.7874 -0.4064)
			(stroke
				(width 0.1524)
				(type default)
			)
			(layer "F.SilkS")
		)
		(fp_line
			(start 0.7874 -0.4064)
			(end 0.7874 0.4064)
			(stroke
				(width 0.1524)
				(type default)
			)
			(layer "F.SilkS")
		)
		(fp_line
			(start 0.7874 0.4064)
			(end -0.7874 0.4064)
			(stroke
				(width 0.1524)
				(type default)
			)
			(layer "F.SilkS")
		)
		(fp_line
			(start -0.67945 -0.305054)
			(end -0.12065 -0.305054)
			(stroke
				(width 0.1)
				(type default)
			)
			(layer "F.Fab")
		)
		(fp_line
			(start -0.67945 0.3048)
			(end -0.67945 -0.305054)
			(stroke
				(width 0.1)
				(type default)
			)
			(layer "F.Fab")
		)
		(fp_line
			(start -0.12065 -0.305054)
			(end -0.12065 -0.2794)
			(stroke
				(width 0.1)
				(type default)
			)
			(layer "F.Fab")
		)
		(fp_line
			(start -0.12065 -0.2794)
			(end 0.12065 -0.2794)
			(stroke
				(width 0.1)
				(type default)
			)
			(layer "F.Fab")
		)
		(fp_line
			(start -0.12065 0.2794)
			(end -0.12065 0.3048)
			(stroke
				(width 0.1)
				(type default)
			)
			(layer "F.Fab")
		)
		(fp_line
			(start -0.12065 0.3048)
			(end -0.67945 0.3048)
			(stroke
				(width 0.1)
				(type default)
			)
			(layer "F.Fab")
		)
		(fp_line
			(start 0.120396 0.2794)
			(end -0.12065 0.2794)
			(stroke
				(width 0.1)
				(type default)
			)
			(layer "F.Fab")
		)
		(fp_line
			(start 0.120396 0.3048)
			(end 0.120396 0.2794)
			(stroke
				(width 0.1)
				(type default)
			)
			(layer "F.Fab")
		)
		(fp_line
			(start 0.12065 -0.3048)
			(end 0.67945 -0.3048)
			(stroke
				(width 0.1)
				(type default)
			)
			(layer "F.Fab")
		)
		(fp_line
			(start 0.12065 -0.2794)
			(end 0.12065 -0.3048)
			(stroke
				(width 0.1)
				(type default)
			)
			(layer "F.Fab")
		)
		(fp_line
			(start 0.67945 -0.3048)
			(end 0.67945 0.3048)
			(stroke
				(width 0.1)
				(type default)
			)
			(layer "F.Fab")
		)
		(fp_line
			(start 0.67945 0.3048)
			(end 0.120396 0.3048)
			(stroke
				(width 0.1)
				(type default)
			)
			(layer "F.Fab")
		)
		(pad "1" smd circle
			(at -0.40005 0)
			(size 0 0)
			(layers "F.Cu" "F.Mask" "F.Paste")
			(net "P3V3_AUX")
		)
		(pad "2" smd circle
			(at 0.40005 0)
			(size 0 0)
			(layers "F.Cu" "F.Mask" "F.Paste")
			(net "PRSNT_SSD14_R_N")
		)
	)
	(footprint ""
		(layer "F.Cu")
		(at 194.164712 -350.098614 90)
		(property "Reference" "C2541"
			(at 0 0 90)
			(layer "F.SilkS")
			(hide yes)
			(effects
				(font
					(size 1.27 1.27)
				)
			)
		)
		(property "Value" ""
			(at 0 0 90)
			(layer "F.Fab")
			(effects
				(font
					(size 1.27 1.27)
				)
			)
		)
		(duplicate_pad_numbers_are_jumpers no)
		(fp_line
			(start 0.299974 -0.150114)
			(end 0.299974 0.150114)
			(stroke
				(width 0.1)
				(type default)
			)
			(layer "F.Fab")
		)
		(fp_line
			(start -0.299974 -0.150114)
			(end 0.299974 -0.150114)
			(stroke
				(width 0.1)
				(type default)
			)
			(layer "F.Fab")
		)
		(fp_line
			(start 0.299974 0.150114)
			(end -0.299974 0.150114)
			(stroke
				(width 0.1)
				(type default)
			)
			(layer "F.Fab")
		)
		(fp_line
			(start -0.299974 0.150114)
			(end -0.299974 -0.150114)
			(stroke
				(width 0.1)
				(type default)
			)
			(layer "F.Fab")
		)
		(pad "1" smd rect
			(at -0.2667 0 90)
			(size 0.3048 0.381)
			(layers "F.Cu" "F.Mask" "F.Paste")
			(net "P5E_PEX1_STN4_TX_DN<65>")
		)
		(pad "2" smd rect
			(at 0.2667 0 90)
			(size 0.3048 0.381)
			(layers "F.Cu" "F.Mask" "F.Paste")
			(net "P5E_PEX1_STN4_TX_C_DN<65>")
		)
	)
	(footprint ""
		(layer "F.Cu")
		(at 144.205198 -307.084984 45)
		(property "Reference" "R1282"
			(at 0 0 45)
			(layer "F.SilkS")
			(hide yes)
			(effects
				(font
					(size 1.27 1.27)
				)
			)
		)
		(property "Value" ""
			(at 0 0 45)
			(layer "F.Fab")
			(effects
				(font
					(size 1.27 1.27)
				)
			)
		)
		(duplicate_pad_numbers_are_jumpers no)
		(fp_line
			(start -0.787389 -0.406267)
			(end 0.787389 -0.406267)
			(stroke
				(width 0.1524)
				(type default)
			)
			(layer "F.SilkS")
		)
		(fp_line
			(start -0.787389 0.406267)
			(end -0.787389 -0.406267)
			(stroke
				(width 0.1524)
				(type default)
			)
			(layer "F.SilkS")
		)
		(fp_line
			(start 0.787389 -0.406267)
			(end 0.787389 0.406267)
			(stroke
				(width 0.1524)
				(type default)
			)
			(layer "F.SilkS")
		)
		(fp_line
			(start 0.787389 0.406267)
			(end -0.787389 0.406267)
			(stroke
				(width 0.1524)
				(type default)
			)
			(layer "F.SilkS")
		)
		(fp_line
			(start -0.679446 -0.305149)
			(end -0.120695 -0.304969)
			(stroke
				(width 0.1)
				(type default)
			)
			(layer "F.Fab")
		)
		(fp_line
			(start -0.120695 -0.304969)
			(end -0.120695 -0.279466)
			(stroke
				(width 0.1)
				(type default)
			)
			(layer "F.Fab")
		)
		(fp_line
			(start -0.120695 -0.279466)
			(end 0.120695 -0.279466)
			(stroke
				(width 0.1)
				(type default)
			)
			(layer "F.Fab")
		)
		(fp_line
			(start -0.679446 0.30479)
			(end -0.679446 -0.305149)
			(stroke
				(width 0.1)
				(type default)
			)
			(layer "F.Fab")
		)
		(fp_line
			(start 0.120515 -0.30479)
			(end 0.679446 -0.30479)
			(stroke
				(width 0.1)
				(type default)
			)
			(layer "F.Fab")
		)
		(fp_line
			(start 0.120695 -0.279466)
			(end 0.120515 -0.30479)
			(stroke
				(width 0.1)
				(type default)
			)
			(layer "F.Fab")
		)
		(fp_line
			(start -0.120695 0.279466)
			(end -0.120515 0.30479)
			(stroke
				(width 0.1)
				(type default)
			)
			(layer "F.Fab")
		)
		(fp_line
			(start -0.120515 0.30479)
			(end -0.679446 0.30479)
			(stroke
				(width 0.1)
				(type default)
			)
			(layer "F.Fab")
		)
		(fp_line
			(start 0.679446 -0.30479)
			(end 0.679446 0.30479)
			(stroke
				(width 0.1)
				(type default)
			)
			(layer "F.Fab")
		)
		(fp_line
			(start 0.120335 0.279466)
			(end -0.120695 0.279466)
			(stroke
				(width 0.1)
				(type default)
			)
			(layer "F.Fab")
		)
		(fp_line
			(start 0.120515 0.30479)
			(end 0.120335 0.279466)
			(stroke
				(width 0.1)
				(type default)
			)
			(layer "F.Fab")
		)
		(fp_line
			(start 0.679446 0.30479)
			(end 0.120515 0.30479)
			(stroke
				(width 0.1)
				(type default)
			)
			(layer "F.Fab")
		)
		(pad "1" smd circle
			(at -0.40005 0 45)
			(size 0 0)
			(layers "F.Cu" "F.Mask" "F.Paste")
			(net "GND")
		)
		(pad "2" smd circle
			(at 0.40005 0 45)
			(size 0 0)
			(layers "F.Cu" "F.Mask" "F.Paste")
			(net "PEX1_DBG_SEL0")
		)
	)
)
